# T6G (Grand Teton) — schematic netlist excerpt (pin names and nets, part order shuffled) for the footprints in the layout excerpt that follows; sources: Cadence DE-HDL packaged netlist, KiCad conversion of 04192023_DAF0TMB3IC0_F0TG_MB_C_brd_V02_OCP.brd

PU54  RAA229621GNPHA0  RAA229621GNP#HA0 IC  pkg QFN40_TH_0-4_5X5XE  page 224
  PWM0  = NC_PVDD11_S3_P1_PWM8
  PWM1  = NC_PVDD11_S3_P1_PWM7
  PWM2  = NC_PVDD11_S3_P1_PWM6
  PWM3  = NC_PVDD11_S3_P1_PWM5
  PWM4  = NC_PVDD11_S3_P1_PWM4
  PWM5  = NC_PVDD11_S3_P1_PWM3
  PWM6  = PVDD11_S3_P1_PWM2
  PWM7  = PVDD11_S3_P1_PWM1
  PMSDA  = PVDD11_S3_P1_PMSDA_R
  PMSCL  = PVDD11_S3_P1_PMSCL_R
  NPMALERT  = PVDD11_S3_P1_PMALERT_R
  PG0  = PWRGD_PVDD11_S3_P1_R
  EN0  = PVDD11_S3_P1_EN_R
  RESET_L  = PVDD11_S3_P1_RESET_N_R
  VDDIO  = PVDD11_S3_P1_VDDIO
  PG1  = NC_PVDD11_S3_P1_PG1
  SVD  = GND
  SVC  = GND
  SVTO  = NC_PVDD11_S3_P1_SVTO
  SVTI  = GND
  VSEN0  = VSENSE_PVDD11_S3_P1_R
  RGND0  = VSENSE_VSS_SENSE_C_P1
  CS7  = PVDD11_S3_P1_IMON1
  CS6  = PVDD11_S3_P1_IMON2
  CS5  = NC_PVDD11_S3_P1_IMON3
  CS4  = NC_PVDD11_S3_P1_IMON4
  CS3  = NC_PVDD11_S3_P1_IMON5
  CS2  = NC_PVDD11_S3_P1_IMON6
  CS1  = NC_PVDD11_S3_P1_IMON7
  CS0  = NC_PVDD11_S3_P1_IMON8
  RGND1  = GND
  VSEN1  = GND
  OCP_L  = PVDD11_S3_P1_OCP_N_R
  \en1||addr_cfg\  = PVDD11_S3_P1_ADDR_CFG
  TEMP1  = PVDD11_S3_P1_TEMP1
  TEMP0  = PVDD11_S3_P1_TEMP0
  \vmon||iinsen\  = PVDD11_S3_P1_VMON
  VINSEN  = PVDD11_S3_P1_VINSEN
  VCC  = PVDD11_S3_P1_VCC
  VCCS  = PVDD11_S3_P1_VCCS
  TH_GND  = GND

(kicad_pcb
	(version 20260206)
	(generator "pcbnew")
	(generator_version "10.0")
	(general
		(thickness 1.6)
		(legacy_teardrops no)
	)
	(paper "A4")
	(title_block
		(title "04192023_DAF0TMB3IC0_F0TG_MB_C_brd_V02_OCP.brd")
		(comment 1 "Grand Teton / footprint 993 of 8354 (PU54), pads 1-41 of 41")
	)
	(layers
		(0 "F.Cu" signal "TOP")
		(4 "In1.Cu" signal "GND")
		(6 "In2.Cu" signal "IN1")
		(8 "In3.Cu" signal "GND1")
		(10 "In4.Cu" signal "IN2")
		(12 "In5.Cu" signal "GND2")
		(14 "In6.Cu" signal "IN3")
		(16 "In7.Cu" signal "GND3")
		(18 "In8.Cu" signal "VCC")
		(20 "In9.Cu" signal "VCC1")
		(22 "In10.Cu" signal "GND4")
		(24 "In11.Cu" signal "IN4")
		(26 "In12.Cu" signal "GND5")
		(28 "In13.Cu" signal "IN5")
		(30 "In14.Cu" signal "GND6")
		(32 "In15.Cu" signal "IN6")
		(34 "In16.Cu" signal "GND7")
		(2 "B.Cu" signal "BOTTOM")
		(9 "F.Adhes" user "F.Adhesive")
		(11 "B.Adhes" user "B.Adhesive")
		(13 "F.Paste" user "Package Geometry/Pastemask Top")
		(15 "B.Paste" user "Package Geometry/Pastemask Bottom")
		(5 "F.SilkS" user "Ref Des/Silkscreen Top")
		(7 "B.SilkS" user "Ref Des/Silkscreen Bottom")
		(1 "F.Mask" user "Board Geometry/Soldermask Top")
		(3 "B.Mask" user "Board Geometry/Soldermask Bottom")
		(17 "Dwgs.User" user "User.Drawings")
		(19 "Cmts.User" user "User.Comments")
		(21 "Eco1.User" user "User.Eco1")
		(23 "Eco2.User" user "User.Eco2")
		(25 "Edge.Cuts" user "Board Geometry/Outline")
		(27 "Margin" user)
		(31 "F.CrtYd" user "Package Geometry/Place Bound Top")
		(29 "B.CrtYd" user "Package Geometry/Place Bound Bottom")
		(35 "F.Fab" user "Ref Des/Assembly Top")
		(33 "B.Fab" user "Ref Des/Assembly Bottom")
	)
	(footprint ""
		(layer "F.Cu")
		(at 162.22853 -348.553278 -90)
		(property "Reference" "PU54"
			(at 1.566926 -7.369048 90)
			(unlocked yes)
			(layer "F.SilkS")
			(effects
				(font
					(size 0.7874 0.5842)
					(thickness 0.1524)
				)
				(justify left)
			)
		)
		(property "Value" ""
			(at 0 0 270)
			(layer "F.Fab")
			(effects
				(font
					(size 1.27 1.27)
				)
			)
		)
		(duplicate_pad_numbers_are_jumpers no)
		(pad "1" smd rect
			(at -2.400046 -1.800098 180)
			(size 0.1778 0.6096)
			(layers "F.Cu" "F.Mask" "F.Paste")
			(net "NC_PVDD11_S3_P1_PWM8")
		)
		(pad "2" smd rect
			(at -2.400046 -1.400048 180)
			(size 0.1778 0.6096)
			(layers "F.Cu" "F.Mask" "F.Paste")
			(net "NC_PVDD11_S3_P1_PWM7")
		)
		(pad "3" smd rect
			(at -2.400046 -0.999998 180)
			(size 0.1778 0.6096)
			(layers "F.Cu" "F.Mask" "F.Paste")
			(net "NC_PVDD11_S3_P1_PWM6")
		)
		(pad "4" smd rect
			(at -2.400046 -0.599948 180)
			(size 0.1778 0.6096)
			(layers "F.Cu" "F.Mask" "F.Paste")
			(net "NC_PVDD11_S3_P1_PWM5")
		)
		(pad "5" smd rect
			(at -2.400046 -0.199898 180)
			(size 0.1778 0.6096)
			(layers "F.Cu" "F.Mask" "F.Paste")
			(net "NC_PVDD11_S3_P1_PWM4")
		)
		(pad "6" smd rect
			(at -2.400046 0.199898 180)
			(size 0.1778 0.6096)
			(layers "F.Cu" "F.Mask" "F.Paste")
			(net "NC_PVDD11_S3_P1_PWM3")
		)
		(pad "7" smd rect
			(at -2.400046 0.599948 180)
			(size 0.1778 0.6096)
			(layers "F.Cu" "F.Mask" "F.Paste")
			(net "PVDD11_S3_P1_PWM2")
		)
		(pad "8" smd rect
			(at -2.400046 0.999998 180)
			(size 0.1778 0.6096)
			(layers "F.Cu" "F.Mask" "F.Paste")
			(net "PVDD11_S3_P1_PWM1")
		)
		(pad "9" smd rect
			(at -2.400046 1.400048 180)
			(size 0.1778 0.6096)
			(layers "F.Cu" "F.Mask" "F.Paste")
			(net "PVDD11_S3_P1_PMSDA_R")
		)
		(pad "10" smd rect
			(at -2.400046 1.800098 180)
			(size 0.1778 0.6096)
			(layers "F.Cu" "F.Mask" "F.Paste")
			(net "PVDD11_S3_P1_PMSCL_R")
		)
		(pad "11" smd rect
			(at -1.800098 2.400046 270)
			(size 0.1778 0.6096)
			(layers "F.Cu" "F.Mask" "F.Paste")
			(net "PVDD11_S3_P1_PMALERT_R")
		)
		(pad "12" smd rect
			(at -1.400048 2.400046 270)
			(size 0.1778 0.6096)
			(layers "F.Cu" "F.Mask" "F.Paste")
			(net "PWRGD_PVDD11_S3_P1_R")
		)
		(pad "13" smd rect
			(at -0.999998 2.400046 270)
			(size 0.1778 0.6096)
			(layers "F.Cu" "F.Mask" "F.Paste")
			(net "PVDD11_S3_P1_EN_R")
		)
		(pad "14" smd rect
			(at -0.599948 2.400046 270)
			(size 0.1778 0.6096)
			(layers "F.Cu" "F.Mask" "F.Paste")
			(net "PVDD11_S3_P1_RESET_N_R")
		)
		(pad "15" smd rect
			(at -0.199898 2.400046 270)
			(size 0.1778 0.6096)
			(layers "F.Cu" "F.Mask" "F.Paste")
			(net "PVDD11_S3_P1_VDDIO")
		)
		(pad "16" smd rect
			(at 0.199898 2.400046 270)
			(size 0.1778 0.6096)
			(layers "F.Cu" "F.Mask" "F.Paste")
			(net "NC_PVDD11_S3_P1_PG1")
		)
		(pad "17" smd rect
			(at 0.599948 2.400046 270)
			(size 0.1778 0.6096)
			(layers "F.Cu" "F.Mask" "F.Paste")
			(net "GND")
		)
		(pad "18" smd rect
			(at 0.999998 2.400046 270)
			(size 0.1778 0.6096)
			(layers "F.Cu" "F.Mask" "F.Paste")
			(net "GND")
		)
		(pad "19" smd rect
			(at 1.400048 2.400046 270)
			(size 0.1778 0.6096)
			(layers "F.Cu" "F.Mask" "F.Paste")
			(net "NC_PVDD11_S3_P1_SVTO")
		)
		(pad "20" smd rect
			(at 1.800098 2.400046 270)
			(size 0.1778 0.6096)
			(layers "F.Cu" "F.Mask" "F.Paste")
			(net "GND")
		)
		(pad "21" smd rect
			(at 2.400046 1.800098 180)
			(size 0.1778 0.6096)
			(layers "F.Cu" "F.Mask" "F.Paste")
			(net "VSENSE_PVDD11_S3_P1_R")
		)
		(pad "22" smd rect
			(at 2.400046 1.400048 180)
			(size 0.1778 0.6096)
			(layers "F.Cu" "F.Mask" "F.Paste")
			(net "VSENSE_VSS_SENSE_C_P1")
		)
		(pad "23" smd rect
			(at 2.400046 0.999998 180)
			(size 0.1778 0.6096)
			(layers "F.Cu" "F.Mask" "F.Paste")
			(net "PVDD11_S3_P1_IMON1")
		)
		(pad "24" smd rect
			(at 2.400046 0.599948 180)
			(size 0.1778 0.6096)
			(layers "F.Cu" "F.Mask" "F.Paste")
			(net "PVDD11_S3_P1_IMON2")
		)
		(pad "25" smd rect
			(at 2.400046 0.199898 180)
			(size 0.1778 0.6096)
			(layers "F.Cu" "F.Mask" "F.Paste")
			(net "NC_PVDD11_S3_P1_IMON3")
		)
		(pad "26" smd rect
			(at 2.400046 -0.199898 180)
			(size 0.1778 0.6096)
			(layers "F.Cu" "F.Mask" "F.Paste")
			(net "NC_PVDD11_S3_P1_IMON4")
		)
		(pad "27" smd rect
			(at 2.400046 -0.599948 180)
			(size 0.1778 0.6096)
			(layers "F.Cu" "F.Mask" "F.Paste")
			(net "NC_PVDD11_S3_P1_IMON5")
		)
		(pad "28" smd rect
			(at 2.400046 -0.999998 180)
			(size 0.1778 0.6096)
			(layers "F.Cu" "F.Mask" "F.Paste")
			(net "NC_PVDD11_S3_P1_IMON6")
		)
		(pad "29" smd rect
			(at 2.400046 -1.400048 180)
			(size 0.1778 0.6096)
			(layers "F.Cu" "F.Mask" "F.Paste")
			(net "NC_PVDD11_S3_P1_IMON7")
		)
		(pad "30" smd rect
			(at 2.400046 -1.800098 180)
			(size 0.1778 0.6096)
			(layers "F.Cu" "F.Mask" "F.Paste")
			(net "NC_PVDD11_S3_P1_IMON8")
		)
		(pad "31" smd rect
			(at 1.800098 -2.400046 270)
			(size 0.1778 0.6096)
			(layers "F.Cu" "F.Mask" "F.Paste")
			(net "GND")
		)
		(pad "32" smd rect
			(at 1.400048 -2.400046 270)
			(size 0.1778 0.6096)
			(layers "F.Cu" "F.Mask" "F.Paste")
			(net "GND")
		)
		(pad "33" smd rect
			(at 0.999998 -2.400046 270)
			(size 0.1778 0.6096)
			(layers "F.Cu" "F.Mask" "F.Paste")
			(net "PVDD11_S3_P1_OCP_N_R")
		)
		(pad "34" smd rect
			(at 0.599948 -2.400046 270)
			(size 0.1778 0.6096)
			(layers "F.Cu" "F.Mask" "F.Paste")
			(net "PVDD11_S3_P1_ADDR_CFG")
		)
		(pad "35" smd rect
			(at 0.199898 -2.400046 270)
			(size 0.1778 0.6096)
			(layers "F.Cu" "F.Mask" "F.Paste")
			(net "PVDD11_S3_P1_TEMP1")
		)
		(pad "36" smd rect
			(at -0.199898 -2.400046 270)
			(size 0.1778 0.6096)
			(layers "F.Cu" "F.Mask" "F.Paste")
			(net "PVDD11_S3_P1_TEMP0")
		)
		(pad "37" smd rect
			(at -0.599948 -2.400046 270)
			(size 0.1778 0.6096)
			(layers "F.Cu" "F.Mask" "F.Paste")
			(net "PVDD11_S3_P1_VMON")
		)
		(pad "38" smd rect
			(at -0.999998 -2.400046 270)
			(size 0.1778 0.6096)
			(layers "F.Cu" "F.Mask" "F.Paste")
			(net "PVDD11_S3_P1_VINSEN")
		)
		(pad "39" smd rect
			(at -1.400048 -2.400046 270)
			(size 0.1778 0.6096)
			(layers "F.Cu" "F.Mask" "F.Paste")
			(net "PVDD11_S3_P1_VCC")
		)
		(pad "40" smd rect
			(at -1.800098 -2.400046 270)
			(size 0.1778 0.6096)
			(layers "F.Cu" "F.Mask" "F.Paste")
			(net "PVDD11_S3_P1_VCCS")
		)
		(pad "TH" smd rect
			(at 0 0 270)
			(size 3.6576 3.6576)
			(layers "F.Cu" "F.Mask" "F.Paste")
			(net "GND")
		)
	)
)
